# S9S_MB_2U (Grand Teton) — schematic netlist excerpt (pin names and nets, part order shuffled) for the footprints in the layout excerpt that follows; sources: Cadence DE-HDL packaged netlist, KiCad conversion of 03242023_DA0F0TMBIJ0_F0T_Motherboard_J_brd_V01_OCP.brd

R907  Q_RES  33.2 1% CHIP  pkg 0402LF  page 114 : A = PWRGD_CHH_CPU1_DIMM1 ; B = PWRGD_FAIL_CPU1_GH
C562  Q_CAP  0.1UF 25V 10% X7R  pkg 0402  page 235 : A = P3V3_AUX ; B = GND

(kicad_pcb
	(version 20260206)
	(generator "pcbnew")
	(generator_version "10.0")
	(general
		(thickness 1.6)
		(legacy_teardrops no)
	)
	(paper "A4")
	(title_block
		(title "03242023_DA0F0TMBIJ0_F0T_Motherboard_J_brd_V01_OCP.brd")
		(comment 1 "Grand Teton / footprints 4916-4917 of 6105")
	)
	(layers
		(0 "F.Cu" signal "TOP")
		(4 "In1.Cu" signal "GND")
		(6 "In2.Cu" signal "IN1")
		(8 "In3.Cu" signal "GND1")
		(10 "In4.Cu" signal "IN2")
		(12 "In5.Cu" signal "GND2")
		(14 "In6.Cu" signal "IN3")
		(16 "In7.Cu" signal "GND3")
		(18 "In8.Cu" signal "VCC")
		(20 "In9.Cu" signal "VCC1")
		(22 "In10.Cu" signal "GND4")
		(24 "In11.Cu" signal "IN4")
		(26 "In12.Cu" signal "GND5")
		(28 "In13.Cu" signal "IN5")
		(30 "In14.Cu" signal "GND6")
		(32 "In15.Cu" signal "IN6")
		(34 "In16.Cu" signal "GND7")
		(2 "B.Cu" signal "BOTTOM")
		(9 "F.Adhes" user "F.Adhesive")
		(11 "B.Adhes" user "B.Adhesive")
		(13 "F.Paste" user "Package Geometry/Pastemask Top")
		(15 "B.Paste" user "Package Geometry/Pastemask Bottom")
		(5 "F.SilkS" user "Ref Des/Silkscreen Top")
		(7 "B.SilkS" user "Ref Des/Silkscreen Bottom")
		(1 "F.Mask" user "Board Geometry/Soldermask Top")
		(3 "B.Mask" user "Board Geometry/Soldermask Bottom")
		(17 "Dwgs.User" user "User.Drawings")
		(19 "Cmts.User" user "User.Comments")
		(21 "Eco1.User" user "User.Eco1")
		(23 "Eco2.User" user "User.Eco2")
		(25 "Edge.Cuts" user "Board Geometry/Outline")
		(27 "Margin" user)
		(31 "F.CrtYd" user "Package Geometry/Place Bound Top")
		(29 "B.CrtYd" user "Package Geometry/Place Bound Bottom")
		(35 "F.Fab" user "Ref Des/Assembly Top")
		(33 "B.Fab" user "Ref Des/Assembly Bottom")
	)
	(footprint ""
		(layer "B.Cu")
		(at 10.373106 -195.816728 -90)
		(property "Reference" "C562"
			(at 0 0 90)
			(layer "B.SilkS")
			(hide yes)
			(effects
				(font
					(size 1.27 1.27)
				)
				(justify mirror)
			)
		)
		(property "Value" ""
			(at 0 0 90)
			(layer "B.Fab")
			(effects
				(font
					(size 1.27 1.27)
				)
				(justify mirror)
			)
		)
		(duplicate_pad_numbers_are_jumpers no)
		(fp_line
			(start -0.7874 0.4064)
			(end 0.7874 0.4064)
			(stroke
				(width 0.1524)
				(type default)
			)
			(layer "B.SilkS")
		)
		(fp_line
			(start 0.7874 0.4064)
			(end 0.7874 -0.4064)
			(stroke
				(width 0.1524)
				(type default)
			)
			(layer "B.SilkS")
		)
		(fp_line
			(start -0.7874 -0.4064)
			(end -0.7874 0.4064)
			(stroke
				(width 0.1524)
				(type default)
			)
			(layer "B.SilkS")
		)
		(fp_line
			(start 0.7874 -0.4064)
			(end -0.7874 -0.4064)
			(stroke
				(width 0.1524)
				(type default)
			)
			(layer "B.SilkS")
		)
		(fp_line
			(start -0.67945 0.3048)
			(end -0.120396 0.3048)
			(stroke
				(width 0.1)
				(type default)
			)
			(layer "B.Fab")
		)
		(fp_line
			(start -0.120396 0.3048)
			(end -0.120396 0.2794)
			(stroke
				(width 0.1)
				(type default)
			)
			(layer "B.Fab")
		)
		(fp_line
			(start 0.12065 0.3048)
			(end 0.67945 0.3048)
			(stroke
				(width 0.1)
				(type default)
			)
			(layer "B.Fab")
		)
		(fp_line
			(start 0.67945 0.3048)
			(end 0.67945 -0.305054)
			(stroke
				(width 0.1)
				(type default)
			)
			(layer "B.Fab")
		)
		(fp_line
			(start -0.120396 0.2794)
			(end 0.12065 0.2794)
			(stroke
				(width 0.1)
				(type default)
			)
			(layer "B.Fab")
		)
		(fp_line
			(start 0.12065 0.2794)
			(end 0.12065 0.3048)
			(stroke
				(width 0.1)
				(type default)
			)
			(layer "B.Fab")
		)
		(fp_line
			(start -0.12065 -0.2794)
			(end -0.12065 -0.3048)
			(stroke
				(width 0.1)
				(type default)
			)
			(layer "B.Fab")
		)
		(fp_line
			(start 0.12065 -0.2794)
			(end -0.12065 -0.2794)
			(stroke
				(width 0.1)
				(type default)
			)
			(layer "B.Fab")
		)
		(fp_line
			(start -0.67945 -0.3048)
			(end -0.67945 0.3048)
			(stroke
				(width 0.1)
				(type default)
			)
			(layer "B.Fab")
		)
		(fp_line
			(start -0.12065 -0.3048)
			(end -0.67945 -0.3048)
			(stroke
				(width 0.1)
				(type default)
			)
			(layer "B.Fab")
		)
		(fp_line
			(start 0.12065 -0.305054)
			(end 0.12065 -0.2794)
			(stroke
				(width 0.1)
				(type default)
			)
			(layer "B.Fab")
		)
		(fp_line
			(start 0.67945 -0.305054)
			(end 0.12065 -0.305054)
			(stroke
				(width 0.1)
				(type default)
			)
			(layer "B.Fab")
		)
		(pad "1" smd circle
			(at 0.40005 0 90)
			(size 0 0)
			(layers "B.Cu" "B.Mask" "B.Paste")
			(net "P3V3_AUX")
		)
		(pad "2" smd circle
			(at -0.40005 0 90)
			(size 0 0)
			(layers "B.Cu" "B.Mask" "B.Paste")
			(net "GND")
		)
	)
	(footprint ""
		(layer "B.Cu")
		(at 215.206834 -318.826642 90)
		(property "Reference" "R907"
			(at 0 0 90)
			(layer "B.SilkS")
			(hide yes)
			(effects
				(font
					(size 1.27 1.27)
				)
				(justify mirror)
			)
		)
		(property "Value" ""
			(at 0 0 90)
			(layer "B.Fab")
			(effects
				(font
					(size 1.27 1.27)
				)
				(justify mirror)
			)
		)
		(duplicate_pad_numbers_are_jumpers no)
		(fp_line
			(start 0.7874 -0.4064)
			(end -0.7874 -0.4064)
			(stroke
				(width 0.1524)
				(type default)
			)
			(layer "B.SilkS")
		)
		(fp_line
			(start -0.7874 -0.4064)
			(end -0.7874 0.4064)
			(stroke
				(width 0.1524)
				(type default)
			)
			(layer "B.SilkS")
		)
		(fp_line
			(start 0.7874 0.4064)
			(end 0.7874 -0.4064)
			(stroke
				(width 0.1524)
				(type default)
			)
			(layer "B.SilkS")
		)
		(fp_line
			(start -0.7874 0.4064)
			(end 0.7874 0.4064)
			(stroke
				(width 0.1524)
				(type default)
			)
			(layer "B.SilkS")
		)
		(fp_line
			(start 0.67945 -0.305054)
			(end 0.12065 -0.305054)
			(stroke
				(width 0.1)
				(type default)
			)
			(layer "B.Fab")
		)
		(fp_line
			(start 0.12065 -0.305054)
			(end 0.12065 -0.2794)
			(stroke
				(width 0.1)
				(type default)
			)
			(layer "B.Fab")
		)
		(fp_line
			(start -0.12065 -0.3048)
			(end -0.67945 -0.3048)
			(stroke
				(width 0.1)
				(type default)
			)
			(layer "B.Fab")
		)
		(fp_line
			(start -0.67945 -0.3048)
			(end -0.67945 0.3048)
			(stroke
				(width 0.1)
				(type default)
			)
			(layer "B.Fab")
		)
		(fp_line
			(start 0.12065 -0.2794)
			(end -0.12065 -0.2794)
			(stroke
				(width 0.1)
				(type default)
			)
			(layer "B.Fab")
		)
		(fp_line
			(start -0.12065 -0.2794)
			(end -0.12065 -0.3048)
			(stroke
				(width 0.1)
				(type default)
			)
			(layer "B.Fab")
		)
		(fp_line
			(start 0.12065 0.2794)
			(end 0.12065 0.3048)
			(stroke
				(width 0.1)
				(type default)
			)
			(layer "B.Fab")
		)
		(fp_line
			(start -0.120396 0.2794)
			(end 0.12065 0.2794)
			(stroke
				(width 0.1)
				(type default)
			)
			(layer "B.Fab")
		)
		(fp_line
			(start 0.67945 0.3048)
			(end 0.67945 -0.305054)
			(stroke
				(width 0.1)
				(type default)
			)
			(layer "B.Fab")
		)
		(fp_line
			(start 0.12065 0.3048)
			(end 0.67945 0.3048)
			(stroke
				(width 0.1)
				(type default)
			)
			(layer "B.Fab")
		)
		(fp_line
			(start -0.120396 0.3048)
			(end -0.120396 0.2794)
			(stroke
				(width 0.1)
				(type default)
			)
			(layer "B.Fab")
		)
		(fp_line
			(start -0.67945 0.3048)
			(end -0.120396 0.3048)
			(stroke
				(width 0.1)
				(type default)
			)
			(layer "B.Fab")
		)
		(pad "1" smd circle
			(at 0.40005 0 270)
			(size 0 0)
			(layers "B.Cu" "B.Mask" "B.Paste")
			(net "PWRGD_CHH_CPU1_DIMM1")
		)
		(pad "2" smd circle
			(at -0.40005 0 270)
			(size 0 0)
			(layers "B.Cu" "B.Mask" "B.Paste")
			(net "PWRGD_FAIL_CPU1_GH")
		)
	)
)
